FILE_TYPE = CONNECTIVITY;
{Allegro Design Entry HDL 16.6-p007 (v16-6-112F) 10/10/2012}
"PAGE_NUMBER" = 81;
0"NC";
1"M_J_DQS_DN<17:0>";
2"M_J_DQS_DP<17:0>";
3"M_J_MA<17:0>";
4"M_J_DQ<63:0>";
5"M_J_CLK_DP<3:0>";
6"M_J_CLK_DN<3:0>";
7"M_J_BG<1:0>";
8"M_J_BA<1:0>";
9"M_J_ECC<7:0>";
10"M_J_CKE<3:0>";
11"M_J_ODT<3:0>";
12"PVDDQ_GHJ\g";
13"GND\g";
14"GND\g";
15"GND\g";
16"PVPP_GHJ\g";
17"PVTT_GHJ\g";
18"PVPP_GHJ\g";
19"P12V_NVDIMM_GHJ\g";
20"GND\g";
21"M_J_CS_N<7:0>";
22"FM_DIMM_EVENT_COD_N";
23"M_J_VREF";
24"TP_CH_J_DIMM_J0_RFU_1";
25"TP_CH_J_DIMM_J0_RFU_0";
26"TP_CH_J_DIMM_J0_RFU_2";
27"SMB_DDR_GHJ_VPP_SCL";
28"SMB_DDR_GHJ_VPP_SDA";
29"FM_ADR_COMPLETE_GHJ_N";
30"M_GHJ_RST_N";
31"M_J_PAR";
32"M_J_C<2>";
33"M_J_CS_N<0>";
34"M_J_CKE<0>";
35"M_J_ODT<1>";
36"M_J_ODT<0>";
37"M_J_ECC<6>";
38"M_J_MA<2>";
39"M_J_BG<0>";
40"M_J_CKE<1>";
41"M_J_ECC<1>";
42"M_J_ECC<0>";
43"M_J_ECC<3>";
44"M_J_ECC<2>";
45"M_J_ECC<5>";
46"M_J_ECC<4>";
47"M_J_ECC<7>";
48"M_J_MA<1>";
49"M_J_MA<0>";
50"M_J_CS_N<1>";
51"M_J_BA<1>";
52"M_J_BA<0>";
53"M_J_BG<1>";
54"M_J_CS_N<2>";
55"M_J_CS_N<3>";
56"M_J_CLK_DN<0>";
57"M_J_CLK_DP<0>";
58"M_J_CLK_DN<1>";
59"M_J_CLK_DP<1>";
60"M_J_ACT_N";
61"M_J_ALERT_N";
62"M_J_DQ<4>";
63"M_J_DQ<5>";
64"M_J_DQ<2>";
65"M_J_DQ<3>";
66"M_J_DQ<46>";
67"M_J_DQ<49>";
68"M_J_DQ<14>";
69"M_J_DQ<27>";
70"M_J_DQ<26>";
71"M_J_DQ<39>";
72"M_J_DQ<37>";
73"M_J_DQ<34>";
74"M_J_DQ<1>";
75"M_J_DQ<0>";
76"M_J_DQ<7>";
77"M_J_DQ<6>";
78"M_J_DQ<9>";
79"M_J_DQ<8>";
80"M_J_DQ<10>";
81"M_J_DQ<13>";
82"M_J_DQ<12>";
83"M_J_DQ<15>";
84"M_J_DQ<17>";
85"M_J_DQ<19>";
86"M_J_DQ<18>";
87"M_J_DQ<21>";
88"M_J_DQ<20>";
89"M_J_DQ<23>";
90"M_J_DQ<22>";
91"M_J_DQ<25>";
92"M_J_DQ<24>";
93"M_J_DQ<31>";
94"M_J_DQ<30>";
95"M_J_DQ<33>";
96"M_J_DQ<32>";
97"M_J_DQ<35>";
98"M_J_DQ<36>";
99"M_J_DQ<38>";
100"M_J_DQ<41>";
101"M_J_DQ<40>";
102"M_J_DQ<43>";
103"M_J_DQ<42>";
104"M_J_DQ<45>";
105"M_J_DQ<44>";
106"M_J_DQ<47>";
107"M_J_DQ<29>";
108"M_J_DQ<28>";
109"M_J_DQ<11>";
110"M_J_DQ<16>";
111"M_J_MA<16>";
112"M_J_MA<15>";
113"M_J_MA<14>";
114"M_J_MA<11>";
115"M_J_MA<10>";
116"M_J_MA<9>";
117"M_J_MA<8>";
118"M_J_MA<7>";
119"M_J_MA<6>";
120"M_J_MA<5>";
121"M_J_MA<4>";
122"M_J_MA<3>";
123"M_J_MA<17>";
124"M_J_MA<13>";
125"M_J_MA<12>";
126"M_J_DQ<62>";
127"M_J_DQ<63>";
128"M_J_DQ<60>";
129"M_J_DQ<48>";
130"M_J_DQ<51>";
131"M_J_DQ<50>";
132"M_J_DQ<53>";
133"M_J_DQ<52>";
134"M_J_DQ<55>";
135"M_J_DQ<59>";
136"M_J_DQ<56>";
137"M_J_DQ<54>";
138"M_J_DQ<57>";
139"M_J_DQ<58>";
140"M_J_DQ<61>";
141"M_J_DQS_DP<6>";
142"M_J_DQS_DN<6>";
143"M_J_DQS_DP<5>";
144"M_J_DQS_DN<5>";
145"M_J_DQS_DP<4>";
146"M_J_DQS_DN<4>";
147"M_J_DQS_DP<3>";
148"M_J_DQS_DN<3>";
149"M_J_DQS_DP<2>";
150"M_J_DQS_DN<2>";
151"M_J_DQS_DP<1>";
152"M_J_DQS_DN<1>";
153"M_J_DQS_DP<0>";
154"M_J_DQS_DN<0>";
155"M_J_DQS_DP<9>";
156"M_J_DQS_DN<9>";
157"M_J_DQS_DP<8>";
158"M_J_DQS_DN<8>";
159"M_J_DQS_DP<7>";
160"M_J_DQS_DN<7>";
161"M_J_DQS_DN<17>";
162"M_J_DQS_DP<16>";
163"M_J_DQS_DN<16>";
164"M_J_DQS_DP<15>";
165"M_J_DQS_DN<15>";
166"M_J_DQS_DP<14>";
167"M_J_DQS_DN<14>";
168"M_J_DQS_DP<13>";
169"M_J_DQS_DN<13>";
170"M_J_DQS_DP<12>";
171"M_J_DQS_DN<12>";
172"M_J_DQS_DP<11>";
173"M_J_DQS_DN<11>";
174"M_J_DQS_DP<10>";
175"M_J_DQS_DN<10>";
176"M_J_DQS_DP<17>";
%"TAP"
"6","(850,4700)","2","mstr_standard","I10";
;
HDL_TAP"TRUE"
BODY_TYPE"PLUMBING"
CDS_LIB"mstr_standard";
"B \NAC \NWC"1;
"S \NAC"
BN"13"169;
%"TAP"
"6","(-1800,2150)","2","mstr_standard","I100";
;
HDL_TAP"TRUE"
BODY_TYPE"PLUMBING"
CDS_LIB"mstr_standard";
"B \NAC \NWC"4;
"S \NAC"
BN"11"109;
%"TAP"
"6","(-1800,2100)","2","mstr_standard","I101";
;
HDL_TAP"TRUE"
BODY_TYPE"PLUMBING"
CDS_LIB"mstr_standard";
"B \NAC \NWC"4;
"S \NAC"
BN"8"79;
%"TAP"
"6","(-1800,2050)","2","mstr_standard","I102";
;
HDL_TAP"TRUE"
BODY_TYPE"PLUMBING"
CDS_LIB"mstr_standard";
"B \NAC \NWC"4;
"S \NAC"
BN"9"78;
%"TAP"
"6","(-1800,2000)","2","mstr_standard","I103";
;
HDL_TAP"TRUE"
BODY_TYPE"PLUMBING"
CDS_LIB"mstr_standard";
"B \NAC \NWC"4;
"S \NAC"
BN"6"77;
%"TAP"
"6","(-1800,1750)","2","mstr_standard","I104";
;
HDL_TAP"TRUE"
BODY_TYPE"PLUMBING"
CDS_LIB"mstr_standard";
"B \NAC \NWC"4;
"S \NAC"
BN"3"65;
%"TAP"
"6","(-1800,1850)","2","mstr_standard","I105";
;
HDL_TAP"TRUE"
BODY_TYPE"PLUMBING"
CDS_LIB"mstr_standard";
"B \NAC \NWC"4;
"S \NAC"
BN"5"63;
%"TAP"
"6","(-1800,1800)","2","mstr_standard","I106";
;
HDL_TAP"TRUE"
BODY_TYPE"PLUMBING"
CDS_LIB"mstr_standard";
"B \NAC \NWC"4;
"S \NAC"
BN"2"64;
%"TAP"
"6","(-1800,1950)","2","mstr_standard","I107";
;
HDL_TAP"TRUE"
BODY_TYPE"PLUMBING"
CDS_LIB"mstr_standard";
"B \NAC \NWC"4;
"S \NAC"
BN"7"76;
%"TAP"
"6","(-1800,1900)","2","mstr_standard","I108";
;
HDL_TAP"TRUE"
BODY_TYPE"PLUMBING"
CDS_LIB"mstr_standard";
"B \NAC \NWC"4;
"S \NAC"
BN"4"62;
%"TAP"
"6","(-1800,1700)","2","mstr_standard","I109";
;
HDL_TAP"TRUE"
BODY_TYPE"PLUMBING"
CDS_LIB"mstr_standard";
"B \NAC \NWC"4;
"S \NAC"
BN"0"75;
%"TAP"
"6","(850,4500)","2","mstr_standard","I11";
;
HDL_TAP"TRUE"
BODY_TYPE"PLUMBING"
CDS_LIB"mstr_standard";
"B \NAC \NWC"1;
"S \NAC"
BN"11"173;
%"TAP"
"6","(-1800,1650)","2","mstr_standard","I110";
;
HDL_TAP"TRUE"
BODY_TYPE"PLUMBING"
CDS_LIB"mstr_standard";
"B \NAC \NWC"4;
"S \NAC"
BN"1"74;
%"TAP"
"6","(-3300,4800)","0","mstr_standard","I112";
;
HDL_TAP"TRUE"
BODY_TYPE"PLUMBING"
CDS_LIB"mstr_standard";
"B \NAC \NWC"3;
"S \NAC"
BN"17"123;
%"TAP"
"6","(-3300,4750)","0","mstr_standard","I114";
;
HDL_TAP"TRUE"
BODY_TYPE"PLUMBING"
CDS_LIB"mstr_standard";
"B \NAC \NWC"3;
"S \NAC"
BN"16"111;
%"TAP"
"6","(-3300,4700)","0","mstr_standard","I115";
;
HDL_TAP"TRUE"
BODY_TYPE"PLUMBING"
CDS_LIB"mstr_standard";
"B \NAC \NWC"3;
"S \NAC"
BN"15"112;
%"TAP"
"6","(-3300,4650)","0","mstr_standard","I116";
;
HDL_TAP"TRUE"
BODY_TYPE"PLUMBING"
CDS_LIB"mstr_standard";
"B \NAC \NWC"3;
"S \NAC"
BN"14"113;
%"TAP"
"6","(-3300,4600)","0","mstr_standard","I117";
;
HDL_TAP"TRUE"
BODY_TYPE"PLUMBING"
CDS_LIB"mstr_standard";
"B \NAC \NWC"3;
"S \NAC"
BN"13"124;
%"TAP"
"6","(-3300,4550)","0","mstr_standard","I118";
;
HDL_TAP"TRUE"
BODY_TYPE"PLUMBING"
CDS_LIB"mstr_standard";
"B \NAC \NWC"3;
"S \NAC"
BN"12"125;
%"TAP"
"6","(-3300,4500)","0","mstr_standard","I119";
;
HDL_TAP"TRUE"
BODY_TYPE"PLUMBING"
CDS_LIB"mstr_standard";
"B \NAC \NWC"3;
"S \NAC"
BN"11"114;
%"TAP"
"6","(650,4750)","2","mstr_standard","I12";
;
HDL_TAP"TRUE"
BODY_TYPE"PLUMBING"
CDS_LIB"mstr_standard";
"B \NAC \NWC"2;
"S \NAC"
BN"13"168;
%"TAP"
"6","(-3300,4450)","0","mstr_standard","I120";
;
HDL_TAP"TRUE"
BODY_TYPE"PLUMBING"
CDS_LIB"mstr_standard";
"B \NAC \NWC"3;
"S \NAC"
BN"10"115;
%"TAP"
"6","(-3300,4400)","0","mstr_standard","I121";
;
HDL_TAP"TRUE"
BODY_TYPE"PLUMBING"
CDS_LIB"mstr_standard";
"B \NAC \NWC"3;
"S \NAC"
BN"9"116;
%"TAP"
"6","(-3300,4350)","0","mstr_standard","I122";
;
HDL_TAP"TRUE"
BODY_TYPE"PLUMBING"
CDS_LIB"mstr_standard";
"B \NAC \NWC"3;
"S \NAC"
BN"8"117;
%"TAP"
"6","(-3300,4300)","0","mstr_standard","I123";
;
HDL_TAP"TRUE"
BODY_TYPE"PLUMBING"
CDS_LIB"mstr_standard";
"B \NAC \NWC"3;
"S \NAC"
BN"7"118;
%"TAP"
"6","(-3300,4250)","0","mstr_standard","I124";
;
HDL_TAP"TRUE"
BODY_TYPE"PLUMBING"
CDS_LIB"mstr_standard";
"B \NAC \NWC"3;
"S \NAC"
BN"6"119;
%"TAP"
"6","(-3300,4200)","0","mstr_standard","I125";
;
HDL_TAP"TRUE"
BODY_TYPE"PLUMBING"
CDS_LIB"mstr_standard";
"B \NAC \NWC"3;
"S \NAC"
BN"5"120;
%"TAP"
"6","(-3300,4150)","0","mstr_standard","I126";
;
HDL_TAP"TRUE"
BODY_TYPE"PLUMBING"
CDS_LIB"mstr_standard";
"B \NAC \NWC"3;
"S \NAC"
BN"4"121;
%"TAP"
"6","(-3300,4100)","0","mstr_standard","I127";
;
HDL_TAP"TRUE"
BODY_TYPE"PLUMBING"
CDS_LIB"mstr_standard";
"B \NAC \NWC"3;
"S \NAC"
BN"3"122;
%"TAP"
"6","(-3300,4050)","0","mstr_standard","I128";
;
HDL_TAP"TRUE"
BODY_TYPE"PLUMBING"
CDS_LIB"mstr_standard";
"B \NAC \NWC"3;
"S \NAC"
BN"2"38;
%"TAP"
"6","(-3300,4000)","0","mstr_standard","I129";
;
HDL_TAP"TRUE"
BODY_TYPE"PLUMBING"
CDS_LIB"mstr_standard";
"B \NAC \NWC"3;
"S \NAC"
BN"1"48;
%"TAP"
"6","(650,4850)","2","mstr_standard","I13";
;
HDL_TAP"TRUE"
BODY_TYPE"PLUMBING"
CDS_LIB"mstr_standard";
"B \NAC \NWC"2;
"S \NAC"
BN"14"166;
%"TAP"
"6","(-3300,3950)","0","mstr_standard","I130";
;
HDL_TAP"TRUE"
BODY_TYPE"PLUMBING"
CDS_LIB"mstr_standard";
"B \NAC \NWC"3;
"S \NAC"
BN"0"49;
%"TAP"
"6","(-3300,3850)","0","mstr_standard","I131";
;
HDL_TAP"TRUE"
BODY_TYPE"PLUMBING"
CDS_LIB"mstr_standard";
"B \NAC \NWC"8;
"S \NAC"
BN"1"51;
%"TAP"
"6","(-3300,3800)","0","mstr_standard","I132";
;
HDL_TAP"TRUE"
BODY_TYPE"PLUMBING"
CDS_LIB"mstr_standard";
"B \NAC \NWC"8;
"S \NAC"
BN"0"52;
%"TAP"
"6","(-3300,3750)","0","mstr_standard","I134";
;
HDL_TAP"TRUE"
BODY_TYPE"PLUMBING"
CDS_LIB"mstr_standard";
"B \NAC \NWC"7;
"S \NAC"
BN"1"53;
%"TAP"
"6","(-3300,3700)","0","mstr_standard","I135";
;
HDL_TAP"TRUE"
BODY_TYPE"PLUMBING"
CDS_LIB"mstr_standard";
"B \NAC \NWC"7;
"S \NAC"
BN"0"39;
%"TAP"
"6","(-3300,2750)","0","mstr_standard","I137";
;
HDL_TAP"TRUE"
BODY_TYPE"PLUMBING"
CDS_LIB"mstr_standard";
"B \NAC \NWC"9;
"S \NAC"
BN"6"37;
%"TAP"
"6","(650,4950)","2","mstr_standard","I14";
;
HDL_TAP"TRUE"
BODY_TYPE"PLUMBING"
CDS_LIB"mstr_standard";
"B \NAC \NWC"2;
"S \NAC"
BN"15"164;
%"TAP"
"6","(-3300,2700)","0","mstr_standard","I140";
;
HDL_TAP"TRUE"
BODY_TYPE"PLUMBING"
CDS_LIB"mstr_standard";
"B \NAC \NWC"9;
"S \NAC"
BN"7"47;
%"TAP"
"6","(-3300,2650)","0","mstr_standard","I141";
;
HDL_TAP"TRUE"
BODY_TYPE"PLUMBING"
CDS_LIB"mstr_standard";
"B \NAC \NWC"9;
"S \NAC"
BN"4"46;
%"TAP"
"6","(-3300,2600)","0","mstr_standard","I142";
;
HDL_TAP"TRUE"
BODY_TYPE"PLUMBING"
CDS_LIB"mstr_standard";
"B \NAC \NWC"9;
"S \NAC"
BN"5"45;
%"TAP"
"6","(-3300,2550)","0","mstr_standard","I143";
;
HDL_TAP"TRUE"
BODY_TYPE"PLUMBING"
CDS_LIB"mstr_standard";
"B \NAC \NWC"9;
"S \NAC"
BN"2"44;
%"TAP"
"6","(-3300,2500)","0","mstr_standard","I144";
;
HDL_TAP"TRUE"
BODY_TYPE"PLUMBING"
CDS_LIB"mstr_standard";
"B \NAC \NWC"9;
"S \NAC"
BN"3"43;
%"TAP"
"6","(-3300,2400)","0","mstr_standard","I145";
;
HDL_TAP"TRUE"
BODY_TYPE"PLUMBING"
CDS_LIB"mstr_standard";
"B \NAC \NWC"9;
"S \NAC"
BN"1"41;
%"TAP"
"6","(-3300,2450)","0","mstr_standard","I146";
;
HDL_TAP"TRUE"
BODY_TYPE"PLUMBING"
CDS_LIB"mstr_standard";
"B \NAC \NWC"9;
"S \NAC"
BN"0"42;
%"TAP"
"6","(650,4650)","2","mstr_standard","I15";
;
HDL_TAP"TRUE"
BODY_TYPE"PLUMBING"
CDS_LIB"mstr_standard";
"B \NAC \NWC"2;
"S \NAC"
BN"12"170;
%"TAP"
"6","(-3600,3600)","0","mstr_standard","I152";
;
HDL_TAP"TRUE"
BODY_TYPE"PLUMBING"
CDS_LIB"mstr_standard";
"B \NAC \NWC"5;
"S \NAC"
BN"1"59;
%"TAP"
"6","(-3600,3500)","0","mstr_standard","I153";
;
HDL_TAP"TRUE"
BODY_TYPE"PLUMBING"
CDS_LIB"mstr_standard";
"B \NAC \NWC"5;
"S \NAC"
BN"0"57;
%"TAP"
"6","(-3750,3550)","0","mstr_standard","I154";
;
HDL_TAP"TRUE"
BODY_TYPE"PLUMBING"
CDS_LIB"mstr_standard";
"B \NAC \NWC"6;
"S \NAC"
BN"1"58;
%"TAP"
"6","(-3750,3450)","0","mstr_standard","I155";
;
HDL_TAP"TRUE"
BODY_TYPE"PLUMBING"
CDS_LIB"mstr_standard";
"B \NAC \NWC"6;
"S \NAC"
BN"0"56;
%"TAP"
"6","(-3300,3300)","0","mstr_standard","I158";
;
HDL_TAP"TRUE"
BODY_TYPE"PLUMBING"
CDS_LIB"mstr_standard";
"B \NAC \NWC"21;
"S \NAC"
BN"3"55;
%"TAP"
"6","(-3300,3250)","0","mstr_standard","I159";
;
HDL_TAP"TRUE"
BODY_TYPE"PLUMBING"
CDS_LIB"mstr_standard";
"B \NAC \NWC"21;
"S \NAC"
BN"2"54;
%"TAP"
"6","(650,4550)","2","mstr_standard","I16";
;
HDL_TAP"TRUE"
BODY_TYPE"PLUMBING"
CDS_LIB"mstr_standard";
"B \NAC \NWC"2;
"S \NAC"
BN"11"172;
%"TAP"
"6","(-3300,3200)","0","mstr_standard","I160";
;
HDL_TAP"TRUE"
BODY_TYPE"PLUMBING"
CDS_LIB"mstr_standard";
"B \NAC \NWC"21;
"S \NAC"
BN"1"50;
%"TAP"
"6","(-3300,3150)","0","mstr_standard","I161";
;
HDL_TAP"TRUE"
BODY_TYPE"PLUMBING"
CDS_LIB"mstr_standard";
"B \NAC \NWC"21;
"S \NAC"
BN"0"33;
%"TAP"
"6","(-3300,3050)","0","mstr_standard","I162";
;
HDL_TAP"TRUE"
BODY_TYPE"PLUMBING"
CDS_LIB"mstr_standard";
"B \NAC \NWC"10;
"S \NAC"
BN"1"40;
%"TAP"
"6","(-3300,3000)","0","mstr_standard","I163";
;
HDL_TAP"TRUE"
BODY_TYPE"PLUMBING"
CDS_LIB"mstr_standard";
"B \NAC \NWC"10;
"S \NAC"
BN"0"34;
%"TAP"
"6","(-3300,2900)","0","mstr_standard","I164";
;
HDL_TAP"TRUE"
BODY_TYPE"PLUMBING"
CDS_LIB"mstr_standard";
"B \NAC \NWC"11;
"S \NAC"
BN"1"35;
%"TAP"
"6","(-3300,2850)","0","mstr_standard","I168";
;
HDL_TAP"TRUE"
BODY_TYPE"PLUMBING"
CDS_LIB"mstr_standard";
"B \NAC \NWC"11;
"S \NAC"
BN"0"36;
%"SCONN288_H44441004"
"4","(-350,2000)","0","mstr_sconn","I169";
;
CDS_SEC"4"
ROOM"DDR4_CH_J"
CDS_LOCATION"J1G3"
SEC"4"
SEC_TYPE"PIP"
CDS_LIB"mstr_sconn"
BOM_COST"MEM"
PACK_TYPE"PIP"
MATERIAL"SCONN"
PART_NUMBER"H44441-004"
LOCATION"J1G3";
"VPP<4>"
$PN"142"16;
"VTT<1>"
$PN"77"17;
"VPP<0>"
$PN"287"16;
"VPP<1>"
$PN"286"16;
"VPP<2>"
$PN"288"16;
"VPP<3>"
$PN"143"16;
"VDD<1>"
$PN"233"12;
"VDD<2>"
$PN"231"12;
"VDD<3>"
$PN"229"12;
"VDD<4>"
$PN"226"12;
"VDD<5>"
$PN"223"12;
"VDD<7>"
$PN"217"12;
"VDD<8>"
$PN"215"12;
"VDD<9>"
$PN"212"12;
"VDD<11>"
$PN"206"12;
"VDD<12>"
$PN"204"12;
"VDD<14>"
$PN"90"12;
"VDD<15>"
$PN"88"12;
"VDD<17>"
$PN"83"12;
"VDD<18>"
$PN"80"12;
"VDD<20>"
$PN"73"12;
"VDD<21>"
$PN"70"12;
"VDD<22>"
$PN"67"12;
"VDD<24>"
$PN"61"12;
"12V<0>"
$PN"145"19;
"12V<1>"
$PN"1"19;
"VTT<0>"
$PN"221"17;
"VDD<25>"
$PN"59"12;
"VDD<23>"
$PN"64"12;
"VDD<19>"
$PN"76"12;
"VDD<16>"
$PN"85"12;
"VDD<13>"
$PN"92"12;
"VDD<10>"
$PN"209"12;
"VDD<6>"
$PN"220"12;
"VDD<0>"
$PN"236"12;
%"PVDDQ_GHJ"
"1","(-1475,2525)","0","mstr_symbols","I17";
;
HDL_POWER"PVDDQ_GHJ"
ROOM"DDR4_CH_J"
BODY_TYPE"PLUMBING"
CDS_LIB"mstr_symbols"
BOM_COST"MEM"
VOLTAGE"1.2V";
"G\NAC"12;
%"GND"
"1","(2450,1100)","2","mstr_symbols","I170";
;
HDL_POWER"GND"
ROOM"DDR4_CH_J"
BODY_TYPE"PLUMBING"
SIZE"1B"
CDS_LIB"mstr_symbols"
BOM_COST"MEM"
VOLTAGE"0";
"A\NAC"13;
%"GND"
"1","(-5200,1750)","2","mstr_symbols","I175";
;
HDL_POWER"GND"
ROOM"DDR4_CH_J"
BODY_TYPE"PLUMBING"
SIZE"1B"
CDS_LIB"mstr_symbols"
BOM_COST"MEM"
VOLTAGE"0";
"A\NAC"14;
%"GND"
"1","(-4550,1200)","0","mstr_symbols","I177";
;
HDL_POWER"GND"
ROOM"DDR4_CH_J"
BODY_TYPE"PLUMBING"
BOM_COST"MEM"
SIZE"1B"
CDS_LIB"mstr_symbols"
VOLTAGE"0";
"A\NAC"15;
%"CAP_A"
"1","(-4550,1450)","2","dev_discrete","I178";
;
ROOM"DDR4_CH_J"
$SEC"1"
CDS_SEC"1"
CDS_LIB"dev_discrete"
BOM_COST"MEM"
CDS_LOCATION"C9U10"
MATERIAL"X7R"
VOLTAGE"25V"
PACK_TYPE"0402V"
TOLERANCE"10%"
VALUE"0.01UF"
PART_NUMBER"A36096-045"
LOCATION"C9U10";
"B"
$PN"2"15;
"A"
$PN"1"23;
%"PVPP_GHJ"
"1","(-1050,3000)","0","mstr_symbols","I179";
;
HDL_POWER"PVPP_GHJ"
ROOM"DDR4_CH_J"
BODY_TYPE"PLUMBING"
CDS_LIB"mstr_symbols"
BOM_COST"MEM"
VOLTAGE"2.5V";
"G\NAC"16;
%"PVTT_GHJ"
"1","(-1200,2700)","0","mstr_symbols","I18";
;
HDL_POWER"PVTT_GHJ"
ROOM"DDR4_CH_J"
BODY_TYPE"PLUMBING"
CDS_LIB"mstr_symbols"
BOM_COST"MEM"
VOLTAGE"0.6V";
"G\NAC"17;
%"PVPP_GHJ"
"1","(-5200,2150)","0","mstr_symbols","I180";
;
HDL_POWER"PVPP_GHJ"
ROOM"DDR4_CH_J"
BODY_TYPE"PLUMBING"
CDS_LIB"mstr_symbols"
BOM_COST"MEM"
VOLTAGE"2.5V";
"G\NAC"18;
%"SCONN288_H44441004"
"3","(1750,2400)","0","mstr_sconn","I185";
;
CDS_SEC"3"
ROOM"DDR4_CH_J"
CDS_LOCATION"J1G3"
SEC"3"
SEC_TYPE"PIP"
CDS_LIB"mstr_sconn"
BOM_COST"MEM"
PACK_TYPE"PIP"
MATERIAL"SCONN"
PART_NUMBER"H44441-004"
LOCATION"J1G3";
"VSS<93>"
$PN"2"20;
"VSS<92>"
$PN"4"20;
"VSS<91>"
$PN"6"20;
"VSS<90>"
$PN"9"20;
"VSS<89>"
$PN"11"20;
"VSS<88>"
$PN"13"20;
"VSS<0>"
$PN"283"13;
"VSS<1>"
$PN"281"13;
"VSS<2>"
$PN"279"13;
"VSS<3>"
$PN"276"13;
"VSS<4>"
$PN"274"13;
"VSS<5>"
$PN"272"13;
"VSS<6>"
$PN"270"13;
"VSS<7>"
$PN"268"13;
"VSS<8>"
$PN"265"13;
"VSS<9>"
$PN"263"13;
"VSS<10>"
$PN"261"13;
"VSS<11>"
$PN"259"13;
"VSS<12>"
$PN"257"13;
"VSS<13>"
$PN"254"13;
"VSS<14>"
$PN"252"13;
"VSS<15>"
$PN"250"13;
"VSS<16>"
$PN"248"13;
"VSS<17>"
$PN"246"13;
"VSS<18>"
$PN"243"13;
"VSS<19>"
$PN"241"13;
"VSS<20>"
$PN"239"13;
"VSS<21>"
$PN"202"13;
"VSS<22>"
$PN"200"13;
"VSS<23>"
$PN"198"13;
"VSS<24>"
$PN"195"13;
"VSS<25>"
$PN"193"13;
"VSS<26>"
$PN"191"13;
"VSS<27>"
$PN"189"13;
"VSS<28>"
$PN"187"13;
"VSS<29>"
$PN"184"13;
"VSS<30>"
$PN"182"13;
"VSS<31>"
$PN"180"13;
"VSS<32>"
$PN"178"13;
"VSS<33>"
$PN"176"13;
"VSS<34>"
$PN"173"13;
"VSS<35>"
$PN"171"13;
"VSS<36>"
$PN"169"13;
"VSS<37>"
$PN"167"13;
"VSS<38>"
$PN"165"13;
"VSS<39>"
$PN"162"13;
"VSS<40>"
$PN"160"13;
"VSS<41>"
$PN"158"13;
"VSS<42>"
$PN"156"13;
"VSS<43>"
$PN"154"13;
"VSS<44>"
$PN"151"13;
"VSS<47>"
$PN"138"20;
"VSS<48>"
$PN"136"20;
"VSS<49>"
$PN"134"20;
"VSS<50>"
$PN"131"20;
"VSS<51>"
$PN"129"20;
"VSS<52>"
$PN"127"20;
"VSS<53>"
$PN"125"20;
"VSS<54>"
$PN"123"20;
"VSS<55>"
$PN"120"20;
"VSS<56>"
$PN"118"20;
"VSS<57>"
$PN"116"20;
"VSS<58>"
$PN"114"20;
"VSS<59>"
$PN"112"20;
"VSS<60>"
$PN"109"20;
"VSS<61>"
$PN"107"20;
"VSS<62>"
$PN"105"20;
"VSS<63>"
$PN"103"20;
"VSS<64>"
$PN"101"20;
"VSS<65>"
$PN"98"20;
"VSS<66>"
$PN"96"20;
"VSS<67>"
$PN"94"20;
"VSS<68>"
$PN"57"20;
"VSS<69>"
$PN"55"20;
"VSS<70>"
$PN"53"20;
"VSS<71>"
$PN"50"20;
"VSS<72>"
$PN"48"20;
"VSS<73>"
$PN"46"20;
"VSS<74>"
$PN"44"20;
"VSS<75>"
$PN"42"20;
"VSS<76>"
$PN"39"20;
"VSS<77>"
$PN"37"20;
"VSS<78>"
$PN"35"20;
"VSS<79>"
$PN"33"20;
"VSS<80>"
$PN"31"20;
"VSS<81>"
$PN"28"20;
"VSS<82>"
$PN"26"20;
"VSS<83>"
$PN"24"20;
"VSS<84>"
$PN"22"20;
"VSS<85>"
$PN"20"20;
"VSS<86>"
$PN"17"20;
"VSS<87>"
$PN"15"20;
"VSS<45>"
$PN"149"13;
"VSS<46>"
$PN"147"13;
%"SCONN288_H44441004"
"1","(-2550,3150)","0","mstr_sconn","I186";
;
CDS_SEC"1"
ROOM"DDR4_CH_J"
CDS_LOCATION"J1G3"
SEC"1"
SEC_TYPE"PIP"
CDS_LIB"mstr_sconn"
BOM_COST"MEM"
PACK_TYPE"PIP"
MATERIAL"SCONN"
PART_NUMBER"H44441-004"
LOCATION"J1G3";
"DQ<63>"
$PN"280"126;
"DQ<62>"
$PN"135"127;
"DQ<61>"
$PN"273"128;
"DQ<5>"
$PN"148"62;
"DQ<4>"
$PN"3"63;
"DQ<3>"
$PN"157"64;
"DQ<2>"
$PN"12"65;
"DQ<47>"
$PN"258"66;
"DQ<48>"
$PN"119"67;
"DQ<49>"
$PN"264"129;
"DQ<50>"
$PN"126"130;
"DQ<51>"
$PN"271"131;
"DQ<52>"
$PN"117"132;
"DQ<53>"
$PN"262"133;
"DQ<54>"
$PN"124"134;
"DQ<58>"
$PN"137"135;
"DQ<57>"
$PN"275"136;
"SAVE_N_NC"
$PN"230"29;
"RFU<1>"
$PN"227"24;
"RFU<0>"
$PN"205"25;
"DQ<17>"
$PN"172"110;
"DQ<15>"
$PN"166"68;
"DQ<26>"
$PN"45"69;
"DQ<27>"
$PN"190"70;
"S0_N"
$PN"84"33;
"CKE<0>"
$PN"60"34;
"ODT<1>"
$PN"91"35;
"ODT<0>"
$PN"87"36;
"CB<7>"
$PN"199"37;
"A16_RAS_N"
$PN"82"111;
"A15_CAS_N"
$PN"86"112;
"A14_WE_N"
$PN"228"113;
"A11"
$PN"210"114;
"A10"
$PN"225"115;
"DQ<38>"
$PN"102"71;
"DQ<36>"
$PN"95"72;
"DQ<35>"
$PN"249"73;
"A2"
$PN"216"38;
"ALERT_N"
$PN"208"61;
"ACT_N"
$PN"62"60;
"DQ<0>"
$PN"5"74;
"DQ<1>"
$PN"150"75;
"SA<1>"
$PN"140"14;
"SA<2>"
$PN"238"18;
"VDDSPD"
$PN"284"18;
"SA<0>"
$PN"139"14;
"BA<0>"
$PN"81"52;
"BG<1>"
$PN"207"53;
"BG<0>"
$PN"63"39;
"CK1P"
$PN"218"59;
"VREFCA"
$PN"146"23;
"SDA"
$PN"285"28;
"SCL"
$PN"141"27;
"RFU<2>"
$PN"144"26;
"RESET_N"
$PN"58"30;
"PAR"
$PN"222"31;
"EVENT_N"
$PN"78"22;
"DQ<6>"
$PN"10"76;
"DQ<7>"
$PN"155"77;
"DQ<8>"
$PN"16"78;
"DQ<9>"
$PN"161"79;
"DQ<10>"
$PN"23"109;
"DQ<11>"
$PN"168"80;
"DQ<12>"
$PN"14"81;
"DQ<13>"
$PN"159"82;
"DQ<14>"
$PN"21"83;
"DQ<16>"
$PN"27"84;
"DQ<18>"
$PN"34"85;
"DQ<19>"
$PN"179"86;
"DQ<20>"
$PN"25"87;
"DQ<21>"
$PN"170"88;
"DQ<22>"
$PN"32"89;
"DQ<23>"
$PN"177"90;
"DQ<24>"
$PN"38"91;
"DQ<25>"
$PN"183"92;
"DQ<30>"
$PN"43"93;
"DQ<31>"
$PN"188"94;
"DQ<32>"
$PN"97"95;
"DQ<33>"
$PN"242"96;
"DQ<34>"
$PN"104"97;
"DQ<37>"
$PN"240"98;
"DQ<39>"
$PN"247"99;
"DQ<40>"
$PN"108"100;
"DQ<41>"
$PN"253"101;
"DQ<42>"
$PN"115"102;
"DQ<43>"
$PN"260"103;
"DQ<44>"
$PN"106"104;
"DQ<45>"
$PN"251"105;
"DQ<46>"
$PN"113"106;
"DQ<55>"
$PN"269"137;
"DQ<56>"
$PN"130"138;
"DQ<59>"
$PN"282"139;
"DQ<60>"
$PN"128"140;
"CKE<1>"
$PN"203"40;
"CK0N"
$PN"75"56;
"CB<0>"
$PN"49"41;
"CB<1>"
$PN"194"42;
"CB<2>"
$PN"56"43;
"CB<3>"
$PN"201"44;
"CB<4>"
$PN"47"45;
"CB<5>"
$PN"192"46;
"CB<6>"
$PN"54"47;
"A9"
$PN"66"116;
"A8"
$PN"68"117;
"A7"
$PN"211"118;
"A6"
$PN"69"119;
"A5"
$PN"213"120;
"A4"
$PN"214"121;
"A3"
$PN"71"122;
"A17"
$PN"234"123;
"A13"
$PN"232"124;
"A12"
$PN"65"125;
"A1"
$PN"72"48;
"A0"
$PN"79"49;
"C<2>"
$PN"235"32;
"DQ<28>"
$PN"36"107;
"DQ<29>"
$PN"181"108;
"S1_N"
$PN"89"50;
"S2_N_C<0>"
$PN"93"54;
"S3_N_C<1>"
$PN"237"55;
"CK0P"
$PN"74"57;
"CK1N"
$PN"219"58;
"BA<1>"
$PN"224"51;
%"P12V_NVDIMM_GHJ"
"1","(350,2975)","0","mstr_symbols","I187";
;
HDL_POWER"P12V_NVDIMM_GHJ"
BODY_TYPE"PLUMBING"
CDS_LIB"mstr_symbols"
VOLTAGE"12.0";
"G\NAC"19;
%"TAP"
"6","(850,4300)","2","mstr_standard","I20";
;
HDL_TAP"TRUE"
BODY_TYPE"PLUMBING"
CDS_LIB"mstr_standard";
"B \NAC \NWC"1;
"S \NAC"
BN"9"156;
%"TAP"
"6","(850,4400)","2","mstr_standard","I21";
;
HDL_TAP"TRUE"
BODY_TYPE"PLUMBING"
CDS_LIB"mstr_standard";
"B \NAC \NWC"1;
"S \NAC"
BN"10"175;
%"TAP"
"6","(850,4200)","2","mstr_standard","I22";
;
HDL_TAP"TRUE"
BODY_TYPE"PLUMBING"
CDS_LIB"mstr_standard";
"B \NAC \NWC"1;
"S \NAC"
BN"8"158;
%"TAP"
"6","(850,4100)","2","mstr_standard","I23";
;
HDL_TAP"TRUE"
BODY_TYPE"PLUMBING"
CDS_LIB"mstr_standard";
"B \NAC \NWC"1;
"S \NAC"
BN"7"160;
%"TAP"
"6","(850,4000)","2","mstr_standard","I24";
;
HDL_TAP"TRUE"
BODY_TYPE"PLUMBING"
CDS_LIB"mstr_standard";
"B \NAC \NWC"1;
"S \NAC"
BN"6"142;
%"TAP"
"6","(650,4250)","2","mstr_standard","I25";
;
HDL_TAP"TRUE"
BODY_TYPE"PLUMBING"
CDS_LIB"mstr_standard";
"B \NAC \NWC"2;
"S \NAC"
BN"8"157;
%"TAP"
"6","(650,4350)","2","mstr_standard","I26";
;
HDL_TAP"TRUE"
BODY_TYPE"PLUMBING"
CDS_LIB"mstr_standard";
"B \NAC \NWC"2;
"S \NAC"
BN"9"155;
%"TAP"
"6","(650,4450)","2","mstr_standard","I27";
;
HDL_TAP"TRUE"
BODY_TYPE"PLUMBING"
CDS_LIB"mstr_standard";
"B \NAC \NWC"2;
"S \NAC"
BN"10"174;
%"TAP"
"6","(650,4150)","2","mstr_standard","I28";
;
HDL_TAP"TRUE"
BODY_TYPE"PLUMBING"
CDS_LIB"mstr_standard";
"B \NAC \NWC"2;
"S \NAC"
BN"7"159;
%"TAP"
"6","(650,4050)","2","mstr_standard","I29";
;
HDL_TAP"TRUE"
BODY_TYPE"PLUMBING"
CDS_LIB"mstr_standard";
"B \NAC \NWC"2;
"S \NAC"
BN"6"141;
%"TAP"
"6","(850,5100)","2","mstr_standard","I3";
;
HDL_TAP"TRUE"
BODY_TYPE"PLUMBING"
CDS_LIB"mstr_standard";
"B \NAC \NWC"1;
"S \NAC"
BN"17"161;
%"TAP"
"6","(850,3900)","2","mstr_standard","I30";
;
HDL_TAP"TRUE"
BODY_TYPE"PLUMBING"
CDS_LIB"mstr_standard";
"B \NAC \NWC"1;
"S \NAC"
BN"5"144;
%"TAP"
"6","(850,3800)","2","mstr_standard","I31";
;
HDL_TAP"TRUE"
BODY_TYPE"PLUMBING"
CDS_LIB"mstr_standard";
"B \NAC \NWC"1;
"S \NAC"
BN"4"146;
%"TAP"
"6","(850,3700)","2","mstr_standard","I32";
;
HDL_TAP"TRUE"
BODY_TYPE"PLUMBING"
CDS_LIB"mstr_standard";
"B \NAC \NWC"1;
"S \NAC"
BN"3"148;
%"TAP"
"6","(850,3600)","2","mstr_standard","I33";
;
HDL_TAP"TRUE"
BODY_TYPE"PLUMBING"
CDS_LIB"mstr_standard";
"B \NAC \NWC"1;
"S \NAC"
BN"2"150;
%"TAP"
"6","(850,3500)","2","mstr_standard","I34";
;
HDL_TAP"TRUE"
BODY_TYPE"PLUMBING"
CDS_LIB"mstr_standard";
"B \NAC \NWC"1;
"S \NAC"
BN"1"152;
%"TAP"
"6","(650,3750)","2","mstr_standard","I35";
;
HDL_TAP"TRUE"
BODY_TYPE"PLUMBING"
CDS_LIB"mstr_standard";
"B \NAC \NWC"2;
"S \NAC"
BN"3"147;
%"TAP"
"6","(650,3850)","2","mstr_standard","I36";
;
HDL_TAP"TRUE"
BODY_TYPE"PLUMBING"
CDS_LIB"mstr_standard";
"B \NAC \NWC"2;
"S \NAC"
BN"4"145;
%"TAP"
"6","(650,3950)","2","mstr_standard","I37";
;
HDL_TAP"TRUE"
BODY_TYPE"PLUMBING"
CDS_LIB"mstr_standard";
"B \NAC \NWC"2;
"S \NAC"
BN"5"143;
%"TAP"
"6","(650,3550)","2","mstr_standard","I38";
;
HDL_TAP"TRUE"
BODY_TYPE"PLUMBING"
CDS_LIB"mstr_standard";
"B \NAC \NWC"2;
"S \NAC"
BN"1"151;
%"TAP"
"6","(650,3450)","2","mstr_standard","I39";
;
HDL_TAP"TRUE"
BODY_TYPE"PLUMBING"
CDS_LIB"mstr_standard";
"B \NAC \NWC"2;
"S \NAC"
BN"0"153;
%"TAP"
"6","(850,5000)","2","mstr_standard","I4";
;
HDL_TAP"TRUE"
BODY_TYPE"PLUMBING"
CDS_LIB"mstr_standard";
"B \NAC \NWC"1;
"S \NAC"
BN"16"163;
%"TAP"
"6","(650,3650)","2","mstr_standard","I40";
;
HDL_TAP"TRUE"
BODY_TYPE"PLUMBING"
CDS_LIB"mstr_standard";
"B \NAC \NWC"2;
"S \NAC"
BN"2"149;
%"TAP"
"6","(850,3400)","2","mstr_standard","I41";
;
HDL_TAP"TRUE"
BODY_TYPE"PLUMBING"
CDS_LIB"mstr_standard";
"B \NAC \NWC"1;
"S \NAC"
BN"0"154;
%"GND"
"1","(1050,1100)","2","mstr_symbols","I44";
;
HDL_POWER"GND"
ROOM"DDR4_CH_J"
BODY_TYPE"PLUMBING"
SIZE"1B"
CDS_LIB"mstr_symbols"
BOM_COST"MEM"
VOLTAGE"0";
"A\NAC"20;
%"TAP"
"6","(-1800,4800)","2","mstr_standard","I46";
;
HDL_TAP"TRUE"
BODY_TYPE"PLUMBING"
CDS_LIB"mstr_standard";
"B \NAC \NWC"4;
"S \NAC"
BN"62"126;
%"TAP"
"6","(-1800,4550)","2","mstr_standard","I47";
;
HDL_TAP"TRUE"
BODY_TYPE"PLUMBING"
CDS_LIB"mstr_standard";
"B \NAC \NWC"4;
"S \NAC"
BN"59"135;
%"TAP"
"6","(-1800,4600)","2","mstr_standard","I48";
;
HDL_TAP"TRUE"
BODY_TYPE"PLUMBING"
CDS_LIB"mstr_standard";
"B \NAC \NWC"4;
"S \NAC"
BN"58"139;
%"TAP"
"6","(-1800,4700)","2","mstr_standard","I49";
;
HDL_TAP"TRUE"
BODY_TYPE"PLUMBING"
CDS_LIB"mstr_standard";
"B \NAC \NWC"4;
"S \NAC"
BN"60"128;
%"TAP"
"6","(650,5150)","2","mstr_standard","I5";
;
HDL_TAP"TRUE"
BODY_TYPE"PLUMBING"
CDS_LIB"mstr_standard";
"B \NAC \NWC"2;
"S \NAC"
BN"17"176;
%"TAP"
"6","(-1800,4650)","2","mstr_standard","I50";
;
HDL_TAP"TRUE"
BODY_TYPE"PLUMBING"
CDS_LIB"mstr_standard";
"B \NAC \NWC"4;
"S \NAC"
BN"61"140;
%"TAP"
"6","(-1800,4750)","2","mstr_standard","I51";
;
HDL_TAP"TRUE"
BODY_TYPE"PLUMBING"
CDS_LIB"mstr_standard";
"B \NAC \NWC"4;
"S \NAC"
BN"63"127;
%"TAP"
"6","(-1800,4450)","2","mstr_standard","I52";
;
HDL_TAP"TRUE"
BODY_TYPE"PLUMBING"
CDS_LIB"mstr_standard";
"B \NAC \NWC"4;
"S \NAC"
BN"57"138;
%"TAP"
"6","(-1800,4400)","2","mstr_standard","I53";
;
HDL_TAP"TRUE"
BODY_TYPE"PLUMBING"
CDS_LIB"mstr_standard";
"B \NAC \NWC"4;
"S \NAC"
BN"54"137;
%"TAP"
"6","(-1800,4350)","2","mstr_standard","I54";
;
HDL_TAP"TRUE"
BODY_TYPE"PLUMBING"
CDS_LIB"mstr_standard";
"B \NAC \NWC"4;
"S \NAC"
BN"55"134;
%"TAP"
"6","(-1800,4300)","2","mstr_standard","I55";
;
HDL_TAP"TRUE"
BODY_TYPE"PLUMBING"
CDS_LIB"mstr_standard";
"B \NAC \NWC"4;
"S \NAC"
BN"52"133;
%"TAP"
"6","(-1800,4500)","2","mstr_standard","I56";
;
HDL_TAP"TRUE"
BODY_TYPE"PLUMBING"
CDS_LIB"mstr_standard";
"B \NAC \NWC"4;
"S \NAC"
BN"56"136;
%"TAP"
"6","(-1800,4200)","2","mstr_standard","I57";
;
HDL_TAP"TRUE"
BODY_TYPE"PLUMBING"
CDS_LIB"mstr_standard";
"B \NAC \NWC"4;
"S \NAC"
BN"50"131;
%"TAP"
"6","(-1800,4150)","2","mstr_standard","I58";
;
HDL_TAP"TRUE"
BODY_TYPE"PLUMBING"
CDS_LIB"mstr_standard";
"B \NAC \NWC"4;
"S \NAC"
BN"51"130;
%"TAP"
"6","(-1800,4100)","2","mstr_standard","I59";
;
HDL_TAP"TRUE"
BODY_TYPE"PLUMBING"
CDS_LIB"mstr_standard";
"B \NAC \NWC"4;
"S \NAC"
BN"48"129;
%"TAP"
"6","(650,5050)","2","mstr_standard","I6";
;
HDL_TAP"TRUE"
BODY_TYPE"PLUMBING"
CDS_LIB"mstr_standard";
"B \NAC \NWC"2;
"S \NAC"
BN"16"162;
%"TAP"
"6","(-1800,4050)","2","mstr_standard","I60";
;
HDL_TAP"TRUE"
BODY_TYPE"PLUMBING"
CDS_LIB"mstr_standard";
"B \NAC \NWC"4;
"S \NAC"
BN"49"67;
%"TAP"
"6","(-1800,4250)","2","mstr_standard","I61";
;
HDL_TAP"TRUE"
BODY_TYPE"PLUMBING"
CDS_LIB"mstr_standard";
"B \NAC \NWC"4;
"S \NAC"
BN"53"132;
%"TAP"
"6","(-1800,3900)","2","mstr_standard","I62";
;
HDL_TAP"TRUE"
BODY_TYPE"PLUMBING"
CDS_LIB"mstr_standard";
"B \NAC \NWC"4;
"S \NAC"
BN"44"105;
%"TAP"
"6","(-1800,3850)","2","mstr_standard","I63";
;
HDL_TAP"TRUE"
BODY_TYPE"PLUMBING"
CDS_LIB"mstr_standard";
"B \NAC \NWC"4;
"S \NAC"
BN"45"104;
%"TAP"
"6","(-1800,3800)","2","mstr_standard","I64";
;
HDL_TAP"TRUE"
BODY_TYPE"PLUMBING"
CDS_LIB"mstr_standard";
"B \NAC \NWC"4;
"S \NAC"
BN"42"103;
%"TAP"
"6","(-1800,3950)","2","mstr_standard","I65";
;
HDL_TAP"TRUE"
BODY_TYPE"PLUMBING"
CDS_LIB"mstr_standard";
"B \NAC \NWC"4;
"S \NAC"
BN"47"106;
%"TAP"
"6","(-1800,4000)","2","mstr_standard","I66";
;
HDL_TAP"TRUE"
BODY_TYPE"PLUMBING"
CDS_LIB"mstr_standard";
"B \NAC \NWC"4;
"S \NAC"
BN"46"66;
%"SCONN288_H44441004"
"2","(-50,4300)","0","mstr_sconn","I67";
;
CDS_SEC"2"
ROOM"DDR4_CH_J"
CDS_LOCATION"J1G3"
SEC"2"
SEC_TYPE"PIP"
CDS_LIB"mstr_sconn"
BOM_COST"MEM"
PACK_TYPE"PIP"
MATERIAL"SCONN"
PART_NUMBER"H44441-004"
LOCATION"J1G3";
"DQS17P"
$PN"51"176;
"DQS9P"
$PN"7"155;
"DQS9N"
$PN"8"156;
"DQS8P"
$PN"197"157;
"DQS8N"
$PN"196"158;
"DQS7P"
$PN"278"159;
"DQS7N"
$PN"277"160;
"DQS6P"
$PN"267"141;
"DQS6N"
$PN"266"142;
"DQS5P"
$PN"256"143;
"DQS5N"
$PN"255"144;
"DQS4P"
$PN"245"145;
"DQS4N"
$PN"244"146;
"DQS3P"
$PN"186"147;
"DQS3N"
$PN"185"148;
"DQS2P"
$PN"175"149;
"DQS2N"
$PN"174"150;
"DQS1P"
$PN"164"151;
"DQS1N"
$PN"163"152;
"DQS17N"
$PN"52"161;
"DQS16P"
$PN"132"162;
"DQS16N"
$PN"133"163;
"DQS15P"
$PN"121"164;
"DQS15N"
$PN"122"165;
"DQS14P"
$PN"110"166;
"DQS14N"
$PN"111"167;
"DQS13P"
$PN"99"168;
"DQS13N"
$PN"100"169;
"DQS12P"
$PN"40"170;
"DQS12N"
$PN"41"171;
"DQS11P"
$PN"29"172;
"DQS11N"
$PN"30"173;
"DQS10P"
$PN"18"174;
"DQS10N"
$PN"19"175;
"DQS0P"
$PN"153"153;
"DQS0N"
$PN"152"154;
%"TAP"
"6","(-1800,3600)","2","mstr_standard","I68";
;
HDL_TAP"TRUE"
BODY_TYPE"PLUMBING"
CDS_LIB"mstr_standard";
"B \NAC \NWC"4;
"S \NAC"
BN"38"99;
%"TAP"
"6","(-1800,3650)","2","mstr_standard","I69";
;
HDL_TAP"TRUE"
BODY_TYPE"PLUMBING"
CDS_LIB"mstr_standard";
"B \NAC \NWC"4;
"S \NAC"
BN"41"100;
%"TAP"
"6","(850,4800)","2","mstr_standard","I7";
;
HDL_TAP"TRUE"
BODY_TYPE"PLUMBING"
CDS_LIB"mstr_standard";
"B \NAC \NWC"1;
"S \NAC"
BN"14"167;
%"TAP"
"6","(-1800,3550)","2","mstr_standard","I70";
;
HDL_TAP"TRUE"
BODY_TYPE"PLUMBING"
CDS_LIB"mstr_standard";
"B \NAC \NWC"4;
"S \NAC"
BN"39"71;
%"TAP"
"6","(-1800,3700)","2","mstr_standard","I71";
;
HDL_TAP"TRUE"
BODY_TYPE"PLUMBING"
CDS_LIB"mstr_standard";
"B \NAC \NWC"4;
"S \NAC"
BN"40"101;
%"TAP"
"6","(-1800,3750)","2","mstr_standard","I72";
;
HDL_TAP"TRUE"
BODY_TYPE"PLUMBING"
CDS_LIB"mstr_standard";
"B \NAC \NWC"4;
"S \NAC"
BN"43"102;
%"TAP"
"6","(-1800,3350)","2","mstr_standard","I73";
;
HDL_TAP"TRUE"
BODY_TYPE"PLUMBING"
CDS_LIB"mstr_standard";
"B \NAC \NWC"4;
"S \NAC"
BN"35"97;
%"TAP"
"6","(-1800,3400)","2","mstr_standard","I74";
;
HDL_TAP"TRUE"
BODY_TYPE"PLUMBING"
CDS_LIB"mstr_standard";
"B \NAC \NWC"4;
"S \NAC"
BN"34"73;
%"TAP"
"6","(-1800,3300)","2","mstr_standard","I75";
;
HDL_TAP"TRUE"
BODY_TYPE"PLUMBING"
CDS_LIB"mstr_standard";
"B \NAC \NWC"4;
"S \NAC"
BN"32"96;
%"TAP"
"6","(-1800,3450)","2","mstr_standard","I76";
;
HDL_TAP"TRUE"
BODY_TYPE"PLUMBING"
CDS_LIB"mstr_standard";
"B \NAC \NWC"4;
"S \NAC"
BN"37"72;
%"TAP"
"6","(-1800,3500)","2","mstr_standard","I77";
;
HDL_TAP"TRUE"
BODY_TYPE"PLUMBING"
CDS_LIB"mstr_standard";
"B \NAC \NWC"4;
"S \NAC"
BN"36"98;
%"TAP"
"6","(-1800,3150)","2","mstr_standard","I78";
;
HDL_TAP"TRUE"
BODY_TYPE"PLUMBING"
CDS_LIB"mstr_standard";
"B \NAC \NWC"4;
"S \NAC"
BN"31"93;
%"TAP"
"6","(-1800,3100)","2","mstr_standard","I79";
;
HDL_TAP"TRUE"
BODY_TYPE"PLUMBING"
CDS_LIB"mstr_standard";
"B \NAC \NWC"4;
"S \NAC"
BN"28"108;
%"TAP"
"6","(850,4900)","2","mstr_standard","I8";
;
HDL_TAP"TRUE"
BODY_TYPE"PLUMBING"
CDS_LIB"mstr_standard";
"B \NAC \NWC"1;
"S \NAC"
BN"15"165;
%"TAP"
"6","(-1800,3050)","2","mstr_standard","I80";
;
HDL_TAP"TRUE"
BODY_TYPE"PLUMBING"
CDS_LIB"mstr_standard";
"B \NAC \NWC"4;
"S \NAC"
BN"29"107;
%"TAP"
"6","(-1800,3200)","2","mstr_standard","I81";
;
HDL_TAP"TRUE"
BODY_TYPE"PLUMBING"
CDS_LIB"mstr_standard";
"B \NAC \NWC"4;
"S \NAC"
BN"30"94;
%"TAP"
"6","(-1800,3250)","2","mstr_standard","I82";
;
HDL_TAP"TRUE"
BODY_TYPE"PLUMBING"
CDS_LIB"mstr_standard";
"B \NAC \NWC"4;
"S \NAC"
BN"33"95;
%"TAP"
"6","(-1800,2850)","2","mstr_standard","I83";
;
HDL_TAP"TRUE"
BODY_TYPE"PLUMBING"
CDS_LIB"mstr_standard";
"B \NAC \NWC"4;
"S \NAC"
BN"25"91;
%"TAP"
"6","(-1800,2900)","2","mstr_standard","I84";
;
HDL_TAP"TRUE"
BODY_TYPE"PLUMBING"
CDS_LIB"mstr_standard";
"B \NAC \NWC"4;
"S \NAC"
BN"24"92;
%"TAP"
"6","(-1800,2800)","2","mstr_standard","I85";
;
HDL_TAP"TRUE"
BODY_TYPE"PLUMBING"
CDS_LIB"mstr_standard";
"B \NAC \NWC"4;
"S \NAC"
BN"22"90;
%"TAP"
"6","(-1800,2750)","2","mstr_standard","I86";
;
HDL_TAP"TRUE"
BODY_TYPE"PLUMBING"
CDS_LIB"mstr_standard";
"B \NAC \NWC"4;
"S \NAC"
BN"23"89;
%"TAP"
"6","(-1800,2950)","2","mstr_standard","I87";
;
HDL_TAP"TRUE"
BODY_TYPE"PLUMBING"
CDS_LIB"mstr_standard";
"B \NAC \NWC"4;
"S \NAC"
BN"27"69;
%"TAP"
"6","(-1800,3000)","2","mstr_standard","I88";
;
HDL_TAP"TRUE"
BODY_TYPE"PLUMBING"
CDS_LIB"mstr_standard";
"B \NAC \NWC"4;
"S \NAC"
BN"26"70;
%"TAP"
"6","(-1800,2650)","2","mstr_standard","I89";
;
HDL_TAP"TRUE"
BODY_TYPE"PLUMBING"
CDS_LIB"mstr_standard";
"B \NAC \NWC"4;
"S \NAC"
BN"21"87;
%"TAP"
"6","(850,4600)","2","mstr_standard","I9";
;
HDL_TAP"TRUE"
BODY_TYPE"PLUMBING"
CDS_LIB"mstr_standard";
"B \NAC \NWC"1;
"S \NAC"
BN"12"171;
%"TAP"
"6","(-1800,2600)","2","mstr_standard","I90";
;
HDL_TAP"TRUE"
BODY_TYPE"PLUMBING"
CDS_LIB"mstr_standard";
"B \NAC \NWC"4;
"S \NAC"
BN"18"86;
%"TAP"
"6","(-1800,2550)","2","mstr_standard","I91";
;
HDL_TAP"TRUE"
BODY_TYPE"PLUMBING"
CDS_LIB"mstr_standard";
"B \NAC \NWC"4;
"S \NAC"
BN"19"85;
%"TAP"
"6","(-1800,2500)","2","mstr_standard","I92";
;
HDL_TAP"TRUE"
BODY_TYPE"PLUMBING"
CDS_LIB"mstr_standard";
"B \NAC \NWC"4;
"S \NAC"
BN"16"110;
%"TAP"
"6","(-1800,2700)","2","mstr_standard","I93";
;
HDL_TAP"TRUE"
BODY_TYPE"PLUMBING"
CDS_LIB"mstr_standard";
"B \NAC \NWC"4;
"S \NAC"
BN"20"88;
%"TAP"
"6","(-1800,2400)","2","mstr_standard","I94";
;
HDL_TAP"TRUE"
BODY_TYPE"PLUMBING"
CDS_LIB"mstr_standard";
"B \NAC \NWC"4;
"S \NAC"
BN"14"68;
%"TAP"
"6","(-1800,2350)","2","mstr_standard","I95";
;
HDL_TAP"TRUE"
BODY_TYPE"PLUMBING"
CDS_LIB"mstr_standard";
"B \NAC \NWC"4;
"S \NAC"
BN"15"83;
%"TAP"
"6","(-1800,2250)","2","mstr_standard","I96";
;
HDL_TAP"TRUE"
BODY_TYPE"PLUMBING"
CDS_LIB"mstr_standard";
"B \NAC \NWC"4;
"S \NAC"
BN"13"81;
%"TAP"
"6","(-1800,2300)","2","mstr_standard","I97";
;
HDL_TAP"TRUE"
BODY_TYPE"PLUMBING"
CDS_LIB"mstr_standard";
"B \NAC \NWC"4;
"S \NAC"
BN"12"82;
%"TAP"
"6","(-1800,2450)","2","mstr_standard","I98";
;
HDL_TAP"TRUE"
BODY_TYPE"PLUMBING"
CDS_LIB"mstr_standard";
"B \NAC \NWC"4;
"S \NAC"
BN"17"84;
%"TAP"
"6","(-1800,2200)","2","mstr_standard","I99";
;
HDL_TAP"TRUE"
BODY_TYPE"PLUMBING"
CDS_LIB"mstr_standard";
"B \NAC \NWC"4;
"S \NAC"
BN"10"80;
END.
